(kicad_pcb
	(version 20260206)
	(generator "pcbnew")
	(generator_version "10.0")
	(general
		(thickness 1.6)
		(legacy_teardrops no)
	)
	(paper "A4")
	(title_block
		(title "Bryce Canyon_F.DPB_16315-1-OCP.brd")
		(comment 1 "Bryce Canyon / footprints 2054-2059 of 2223")
	)
	(layers
		(0 "F.Cu" signal "TOP")
		(4 "In1.Cu" signal "L2GND")
		(6 "In2.Cu" signal "L3")
		(8 "In3.Cu" signal "L4GND")
		(10 "In4.Cu" signal "L5")
		(12 "In5.Cu" signal "L6VCC")
		(14 "In6.Cu" signal "L7VCC")
		(16 "In7.Cu" signal "L8")
		(18 "In8.Cu" signal "L9GND")
		(20 "In9.Cu" signal "L10")
		(22 "In10.Cu" signal "L11GND")
		(2 "B.Cu" signal "BOTTOM")
		(9 "F.Adhes" user "F.Adhesive")
		(11 "B.Adhes" user "B.Adhesive")
		(13 "F.Paste" user "Package Geometry/Pastemask Top")
		(15 "B.Paste" user "Package Geometry/Pastemask Bottom")
		(5 "F.SilkS" user "Ref Des/Silkscreen Top")
		(7 "B.SilkS" user "Ref Des/Silkscreen Bottom")
		(1 "F.Mask" user "Board Geometry/Soldermask Top")
		(3 "B.Mask" user "Board Geometry/Soldermask Bottom")
		(17 "Dwgs.User" user "User.Drawings")
		(19 "Cmts.User" user "User.Comments")
		(21 "Eco1.User" user "User.Eco1")
		(23 "Eco2.User" user "User.Eco2")
		(25 "Edge.Cuts" user "Board Geometry/Outline")
		(27 "Margin" user)
		(31 "F.CrtYd" user "Package Geometry/Place Bound Top")
		(29 "B.CrtYd" user "Package Geometry/Place Bound Bottom")
		(35 "F.Fab" user "Ref Des/Assembly Top")
		(33 "B.Fab" user "Ref Des/Assembly Bottom")
	)
	(footprint ""
		(layer "B.Cu")
		(at 46.355 -144.0688 -90)
		(property "Reference" "U21"
			(at 0 0 90)
			(layer "B.SilkS")
			(hide yes)
			(effects
				(font
					(size 1.27 1.27)
				)
				(justify mirror)
			)
		)
		(property "Value" "TPS53319DQPR-GP"
			(at -4.7498 -5.6896 270)
			(unlocked yes)
			(layer "B.Fab")
			(hide yes)
			(effects
				(font
					(size 1.016 1.016)
					(thickness 0.1524)
				)
				(justify mirror)
			)
		)
		(property "Device Type" "QFN22G6050-G6133H60"
			(at -4.7498 -7.2136 270)
			(unlocked yes)
			(layer "B.Fab")
			(hide yes)
			(effects
				(font
					(size 1.016 1.016)
					(thickness 0.1524)
				)
				(justify mirror)
			)
		)
		(duplicate_pad_numbers_are_jumpers no)
		(fp_line
			(start -3.556 3.5179)
			(end -3.556 2.2479)
			(stroke
				(width 0.1524)
				(type default)
			)
			(layer "B.SilkS")
		)
		(fp_line
			(start -2.286 3.5179)
			(end -3.556 3.5179)
			(stroke
				(width 0.1524)
				(type default)
			)
			(layer "B.SilkS")
		)
		(fp_line
			(start 3.556 3.5179)
			(end 2.286 3.5179)
			(stroke
				(width 0.1524)
				(type default)
			)
			(layer "B.SilkS")
		)
		(fp_line
			(start -1.500124 3.262122)
			(end -1.500124 4.024122)
			(stroke
				(width 0.1524)
				(type default)
			)
			(layer "B.SilkS")
		)
		(fp_line
			(start 0.999998 3.262122)
			(end 0.999998 3.770122)
			(stroke
				(width 0.1524)
				(type default)
			)
			(layer "B.SilkS")
		)
		(fp_line
			(start 3.556 2.2479)
			(end 3.556 3.5179)
			(stroke
				(width 0.1524)
				(type default)
			)
			(layer "B.SilkS")
		)
		(fp_line
			(start -0.500126 -3.262122)
			(end -0.500126 -3.770122)
			(stroke
				(width 0.1524)
				(type default)
			)
			(layer "B.SilkS")
		)
		(fp_line
			(start 1.999996 -3.262122)
			(end 1.999996 -4.024122)
			(stroke
				(width 0.1524)
				(type default)
			)
			(layer "B.SilkS")
		)
		(fp_line
			(start 2.286 -3.5179)
			(end 3.556 -3.5179)
			(stroke
				(width 0.1524)
				(type default)
			)
			(layer "B.SilkS")
		)
		(fp_line
			(start 3.556 -3.5179)
			(end 3.556 -2.2479)
			(stroke
				(width 0.1524)
				(type default)
			)
			(layer "B.SilkS")
		)
		(fp_poly
			(pts
				(xy -3.556 -3.5179) (xy -2.5273 -3.5179) (xy -3.556 -2.4892)
			)
			(stroke
				(width 0)
				(type default)
			)
			(fill yes)
			(layer "B.SilkS")
		)
		(fp_rect
			(start 2.9972 2.5019)
			(end -2.9972 -2.5019)
			(stroke
				(width 0)
				(type default)
			)
			(fill no)
			(layer "B.CrtYd")
		)
		(fp_poly
			(pts
				(xy -3.556 -2.5019) (xy 2.9972 -2.5019) (xy 2.9972 2.5019) (xy -2.9972 2.5019) (xy -2.9972 -2.4892)
				(xy -3.556 -2.4892) (xy -3.556 3.5179) (xy 3.556 3.5179) (xy 3.556 -3.5179) (xy -3.556 -3.5179)
			)
			(stroke
				(width 0)
				(type default)
			)
			(fill no)
			(layer "B.CrtYd")
		)
		(fp_rect
			(start 3.556 3.5179)
			(end -3.556 -3.5179)
			(stroke
				(width 0)
				(type default)
			)
			(fill no)
			(layer "B.Fab")
		)
		(pad "1" smd rect
			(at -2.500122 -2.449322 90)
			(size 0.3048 1.1176)
			(layers "B.Cu" "B.Mask" "B.Paste")
			(net "P5V_B_VFB")
		)
		(pad "2" smd rect
			(at -1.999996 -2.449322 90)
			(size 0.3048 1.1176)
			(layers "B.Cu" "B.Mask" "B.Paste")
			(net "P5V_B_EN_R")
		)
		(pad "3" smd rect
			(at -1.500124 -2.449322 90)
			(size 0.3048 1.1176)
			(layers "B.Cu" "B.Mask" "B.Paste")
			(net "P5V_A_2_PGOOD")
		)
		(pad "4" smd rect
			(at -0.999998 -2.449322 90)
			(size 0.3048 1.1176)
			(layers "B.Cu" "B.Mask" "B.Paste")
			(net "P5V_B_VBST")
		)
		(pad "5" smd rect
			(at -0.500126 -2.449322 90)
			(size 0.3048 1.1176)
			(layers "B.Cu" "B.Mask" "B.Paste")
			(net "P5V_B_ROVP")
		)
		(pad "6" smd rect
			(at 0 -2.449322 90)
			(size 0.3048 1.1176)
			(layers "B.Cu" "B.Mask" "B.Paste")
			(net "P5V_B_LL")
		)
		(pad "7" smd rect
			(at 0.500126 -2.449322 90)
			(size 0.3048 1.1176)
			(layers "B.Cu" "B.Mask" "B.Paste")
			(net "P5V_B_LL")
		)
		(pad "8" smd rect
			(at 0.999998 -2.449322 90)
			(size 0.3048 1.1176)
			(layers "B.Cu" "B.Mask" "B.Paste")
			(net "P5V_B_LL")
		)
		(pad "9" smd rect
			(at 1.500124 -2.449322 90)
			(size 0.3048 1.1176)
			(layers "B.Cu" "B.Mask" "B.Paste")
			(net "P5V_B_LL")
		)
		(pad "10" smd rect
			(at 1.999996 -2.449322 90)
			(size 0.3048 1.1176)
			(layers "B.Cu" "B.Mask" "B.Paste")
			(net "P5V_B_LL")
		)
		(pad "11" smd rect
			(at 2.500122 -2.449322 90)
			(size 0.3048 1.1176)
			(layers "B.Cu" "B.Mask" "B.Paste")
			(net "P5V_B_LL")
		)
		(pad "12" smd rect
			(at 2.500122 2.449322 90)
			(size 0.3048 1.1176)
			(layers "B.Cu" "B.Mask" "B.Paste")
			(net "P12V_A_VIN_U21")
		)
		(pad "13" smd rect
			(at 1.999996 2.449322 90)
			(size 0.3048 1.1176)
			(layers "B.Cu" "B.Mask" "B.Paste")
			(net "P12V_A_VIN_U21")
		)
		(pad "14" smd rect
			(at 1.500124 2.449322 90)
			(size 0.3048 1.1176)
			(layers "B.Cu" "B.Mask" "B.Paste")
			(net "P12V_A_VIN_U21")
		)
		(pad "15" smd rect
			(at 0.999998 2.449322 90)
			(size 0.3048 1.1176)
			(layers "B.Cu" "B.Mask" "B.Paste")
			(net "P12V_A_VIN_U21")
		)
		(pad "16" smd rect
			(at 0.500126 2.449322 90)
			(size 0.3048 1.1176)
			(layers "B.Cu" "B.Mask" "B.Paste")
			(net "P12V_A_VIN_U21")
		)
		(pad "17" smd rect
			(at 0 2.449322 90)
			(size 0.3048 1.1176)
			(layers "B.Cu" "B.Mask" "B.Paste")
			(net "P12V_A_VIN_U21")
		)
		(pad "18" smd rect
			(at -0.500126 2.449322 90)
			(size 0.3048 1.1176)
			(layers "B.Cu" "B.Mask" "B.Paste")
			(net "P5V_B_VREG")
		)
		(pad "19" smd rect
			(at -0.999998 2.449322 90)
			(size 0.3048 1.1176)
			(layers "B.Cu" "B.Mask" "B.Paste")
			(net "P12V_A_VDD_U21")
		)
		(pad "20" smd rect
			(at -1.500124 2.449322 90)
			(size 0.3048 1.1176)
			(layers "B.Cu" "B.Mask" "B.Paste")
			(net "P5V_B_MODE")
		)
		(pad "21" smd rect
			(at -1.999996 2.449322 90)
			(size 0.3048 1.1176)
			(layers "B.Cu" "B.Mask" "B.Paste")
			(net "P5V_B_TRIP")
		)
		(pad "22" smd rect
			(at -2.500122 2.449322 90)
			(size 0.3048 1.1176)
			(layers "B.Cu" "B.Mask" "B.Paste")
			(net "P5V_B_RF")
		)
		(pad "23" smd custom
			(at 0 0 90)
			(size 0.83185 0.83185)
			(layers "B.Cu" "B.Mask" "B.Paste")
			(net "GND")
			(options
				(clearance outline)
				(anchor circle)
			)
			(primitives
				(gr_poly
					(pts
						(xy -2.7813 -1.6637) (xy -2.7813 -1.2954) (xy -3.048 -1.2954) (xy -3.048 -0.9525) (xy -2.7813 -0.9525)
						(xy -2.7813 0.9525) (xy -3.048 0.9525) (xy -3.048 1.2954) (xy -2.7813 1.2954) (xy -2.7813 1.6637)
						(xy 2.7813 1.6637) (xy 2.7813 1.2954) (xy 3.048 1.2954) (xy 3.048 0.9525) (xy 2.7813 0.9525) (xy 2.7813 -0.9525)
						(xy 3.048 -0.9525) (xy 3.048 -1.2954) (xy 2.7813 -1.2954) (xy 2.7813 -1.6637)
					)
					(width 0)
					(fill yes)
				)
			)
		)
	)
	(footprint ""
		(layer "B.Cu")
		(at 189.377828 -240.284508 90)
		(property "Reference" "C681"
			(at 0 0 90)
			(layer "B.SilkS")
			(hide yes)
			(effects
				(font
					(size 1.27 1.27)
				)
				(justify mirror)
			)
		)
		(property "Value" "SC10U6D3V5KX-4GP"
			(at 0.0762 -6.1214 90)
			(unlocked yes)
			(layer "B.Fab")
			(hide yes)
			(effects
				(font
					(size 1.016 1.016)
					(thickness 0.1524)
				)
				(justify mirror)
			)
		)
		(property "Device Type" "C805H58"
			(at 0.0762 -8.1534 90)
			(unlocked yes)
			(layer "B.Fab")
			(hide yes)
			(effects
				(font
					(size 1.016 1.016)
					(thickness 0.1524)
				)
				(justify mirror)
			)
		)
		(duplicate_pad_numbers_are_jumpers no)
		(fp_line
			(start -0.635 0)
			(end 0.635 0)
			(stroke
				(width 0.508)
				(type default)
			)
			(layer "B.SilkS")
		)
		(fp_rect
			(start 0.9652 1.778)
			(end -0.9652 -1.778)
			(stroke
				(width 0)
				(type default)
			)
			(fill no)
			(layer "B.CrtYd")
		)
		(fp_poly
			(pts
				(xy 0.9652 -1.778) (xy -0.9652 -1.778) (xy -0.9652 1.778) (xy 0.9652 1.778)
			)
			(stroke
				(width 0)
				(type default)
			)
			(fill no)
			(layer "B.Fab")
		)
		(pad "1" smd rect
			(at 0 -0.9652 270)
			(size 1.397 1.143)
			(layers "B.Cu" "B.Mask" "B.Paste")
			(net "P3V3_STBY_A")
		)
		(pad "2" smd rect
			(at 0 0.9652 270)
			(size 1.397 1.143)
			(layers "B.Cu" "B.Mask" "B.Paste")
			(net "GND")
		)
	)
	(footprint ""
		(layer "B.Cu")
		(at 484.109522 -228.4095 180)
		(property "Reference" "R1263"
			(at 0 0 0)
			(layer "B.SilkS")
			(hide yes)
			(effects
				(font
					(size 1.27 1.27)
				)
				(justify mirror)
			)
		)
		(property "Value" "0R2J-2-GP"
			(at -0.064008 -3.993896 180)
			(unlocked yes)
			(layer "B.Fab")
			(hide yes)
			(effects
				(font
					(size 1.016 1.016)
					(thickness 0.1524)
				)
				(justify mirror)
			)
		)
		(property "Device Type" "R402H16"
			(at -0.064008 -5.517896 180)
			(unlocked yes)
			(layer "B.Fab")
			(hide yes)
			(effects
				(font
					(size 1.016 1.016)
					(thickness 0.1524)
				)
				(justify mirror)
			)
		)
		(duplicate_pad_numbers_are_jumpers no)
		(fp_line
			(start 0.508 -0.9398)
			(end 0.508 0.9398)
			(stroke
				(width 0.1524)
				(type default)
			)
			(layer "B.SilkS")
		)
		(fp_line
			(start -0.508 -0.9398)
			(end 0.508 -0.9398)
			(stroke
				(width 0.1524)
				(type default)
			)
			(layer "B.SilkS")
		)
		(fp_rect
			(start 0.508 0.9398)
			(end -0.508 -0.9398)
			(stroke
				(width 0)
				(type default)
			)
			(fill no)
			(layer "B.CrtYd")
		)
		(fp_rect
			(start 0.508 0.9398)
			(end -0.508 -0.9398)
			(stroke
				(width 0)
				(type default)
			)
			(fill no)
			(layer "B.Fab")
		)
		(pad "1" smd custom
			(at 0 -0.4445)
			(size 0.1397 0.1397)
			(layers "B.Cu" "B.Mask" "B.Paste")
			(net "P12V_A_PGOOD")
			(options
				(clearance outline)
				(anchor circle)
			)
			(primitives
				(gr_poly
					(pts
						(arc
							(start -0.1778 0.2794)
							(mid -0.249642 0.249642)
							(end -0.2794 0.1778)
						)
						(arc
							(start -0.2794 -0.1778)
							(mid -0.249642 -0.249642)
							(end -0.1778 -0.2794)
						)
						(arc
							(start 0.1778 -0.2794)
							(mid 0.249642 -0.249642)
							(end 0.2794 -0.1778)
						)
						(arc
							(start 0.2794 0.1778)
							(mid 0.249642 0.249642)
							(end 0.1778 0.2794)
						)
					)
					(width 0)
					(fill yes)
				)
			)
		)
		(pad "2" smd custom
			(at 0 0.4445)
			(size 0.1397 0.1397)
			(layers "B.Cu" "B.Mask" "B.Paste")
			(net "P5V_D_EN_R")
			(options
				(clearance outline)
				(anchor circle)
			)
			(primitives
				(gr_poly
					(pts
						(arc
							(start -0.1778 0.2794)
							(mid -0.249642 0.249642)
							(end -0.2794 0.1778)
						)
						(arc
							(start -0.2794 -0.1778)
							(mid -0.249642 -0.249642)
							(end -0.1778 -0.2794)
						)
						(arc
							(start 0.1778 -0.2794)
							(mid 0.249642 -0.249642)
							(end 0.2794 -0.1778)
						)
						(arc
							(start 0.2794 0.1778)
							(mid 0.249642 0.249642)
							(end 0.1778 0.2794)
						)
					)
					(width 0)
					(fill yes)
				)
			)
		)
	)
	(footprint ""
		(layer "B.Cu")
		(at 32.959802 -141.66215 180)
		(property "Reference" "R1226"
			(at 0 0 0)
			(layer "B.SilkS")
			(hide yes)
			(effects
				(font
					(size 1.27 1.27)
				)
				(justify mirror)
			)
		)
		(property "Value" "2D2R3-1-U-GP"
			(at 0.0254 -2.5146 180)
			(unlocked yes)
			(layer "B.Fab")
			(hide yes)
			(effects
				(font
					(size 1.016 1.016)
					(thickness 0.1524)
				)
				(justify mirror)
			)
		)
		(property "Device Type" "R603H22"
			(at 0.0254 -4.0386 180)
			(unlocked yes)
			(layer "B.Fab")
			(hide yes)
			(effects
				(font
					(size 1.016 1.016)
					(thickness 0.1524)
				)
				(justify mirror)
			)
		)
		(duplicate_pad_numbers_are_jumpers no)
		(fp_line
			(start 0.4826 0)
			(end 0.2032 0)
			(stroke
				(width 0.2032)
				(type default)
			)
			(layer "B.SilkS")
		)
		(fp_line
			(start -0.2032 0)
			(end -0.4826 0)
			(stroke
				(width 0.2032)
				(type default)
			)
			(layer "B.SilkS")
		)
		(fp_rect
			(start 0.5842 1.3335)
			(end -0.5842 -1.3335)
			(stroke
				(width 0)
				(type default)
			)
			(fill no)
			(layer "B.CrtYd")
		)
		(fp_rect
			(start 0.5842 1.3335)
			(end -0.5842 -1.3335)
			(stroke
				(width 0)
				(type default)
			)
			(fill no)
			(layer "B.Fab")
		)
		(pad "1" smd custom
			(at 0 -0.762)
			(size 0.2159 0.2159)
			(layers "B.Cu" "B.Mask" "B.Paste")
			(net "P12V_A")
			(options
				(clearance outline)
				(anchor circle)
			)
			(primitives
				(gr_poly
					(pts
						(arc
							(start -0.3302 0.4318)
							(mid -0.402042 0.402042)
							(end -0.4318 0.3302)
						)
						(arc
							(start -0.4318 -0.3302)
							(mid -0.402042 -0.402042)
							(end -0.3302 -0.4318)
						)
						(arc
							(start 0.3302 -0.4318)
							(mid 0.402042 -0.402042)
							(end 0.4318 -0.3302)
						)
						(arc
							(start 0.4318 0.3302)
							(mid 0.402042 0.402042)
							(end 0.3302 0.4318)
						)
					)
					(width 0)
					(fill yes)
				)
			)
		)
		(pad "2" smd custom
			(at 0 0.762)
			(size 0.2159 0.2159)
			(layers "B.Cu" "B.Mask" "B.Paste")
			(net "P12V_A_VDD_U21")
			(options
				(clearance outline)
				(anchor circle)
			)
			(primitives
				(gr_poly
					(pts
						(arc
							(start -0.3302 0.4318)
							(mid -0.402042 0.402042)
							(end -0.4318 0.3302)
						)
						(arc
							(start -0.4318 -0.3302)
							(mid -0.402042 -0.402042)
							(end -0.3302 -0.4318)
						)
						(arc
							(start 0.3302 -0.4318)
							(mid 0.402042 -0.402042)
							(end 0.4318 -0.3302)
						)
						(arc
							(start 0.4318 0.3302)
							(mid 0.402042 0.402042)
							(end 0.3302 0.4318)
						)
					)
					(width 0)
					(fill yes)
				)
			)
		)
	)
	(footprint ""
		(layer "B.Cu")
		(at 469.1888 -252.5522 180)
		(property "Reference" "C647"
			(at 0 0 0)
			(layer "B.SilkS")
			(hide yes)
			(effects
				(font
					(size 1.27 1.27)
				)
				(justify mirror)
			)
		)
		(property "Value" "SC10U16V5KX-7-GP-U"
			(at 0.0762 -6.1214 180)
			(unlocked yes)
			(layer "B.Fab")
			(hide yes)
			(effects
				(font
					(size 1.016 1.016)
					(thickness 0.1524)
				)
				(justify mirror)
			)
		)
		(property "Device Type" "C805H58"
			(at 0.0762 -8.1534 180)
			(unlocked yes)
			(layer "B.Fab")
			(hide yes)
			(effects
				(font
					(size 1.016 1.016)
					(thickness 0.1524)
				)
				(justify mirror)
			)
		)
		(duplicate_pad_numbers_are_jumpers no)
		(fp_line
			(start -0.635 0)
			(end 0.635 0)
			(stroke
				(width 0.508)
				(type default)
			)
			(layer "B.SilkS")
		)
		(fp_rect
			(start 0.9652 1.778)
			(end -0.9652 -1.778)
			(stroke
				(width 0)
				(type default)
			)
			(fill no)
			(layer "B.CrtYd")
		)
		(fp_poly
			(pts
				(xy 0.9652 -1.778) (xy -0.9652 -1.778) (xy -0.9652 1.778) (xy 0.9652 1.778)
			)
			(stroke
				(width 0)
				(type default)
			)
			(fill no)
			(layer "B.Fab")
		)
		(pad "1" smd rect
			(at 0 -0.9652)
			(size 1.397 1.143)
			(layers "B.Cu" "B.Mask" "B.Paste")
			(net "P5V_A_3")
		)
		(pad "2" smd rect
			(at 0 0.9652)
			(size 1.397 1.143)
			(layers "B.Cu" "B.Mask" "B.Paste")
			(net "GND")
		)
	)
	(footprint ""
		(layer "B.Cu")
		(at 28.956 -253.3142)
		(property "Reference" "PG11"
			(at 0 0 0)
			(layer "B.SilkS")
			(hide yes)
			(effects
				(font
					(size 1.27 1.27)
				)
				(justify mirror)
			)
		)
		(property "Value" "COPPER-CLOSE-GP-U"
			(at -0.0762 -2.8702 0)
			(unlocked yes)
			(layer "B.Fab")
			(hide yes)
			(effects
				(font
					(size 1.016 1.016)
					(thickness 0.1524)
				)
				(justify mirror)
			)
		)
		(property "Device Type" "CON2C-U"
			(at -0.0762 -4.3942 0)
			(unlocked yes)
			(layer "B.Fab")
			(hide yes)
			(effects
				(font
					(size 1.016 1.016)
					(thickness 0.1524)
				)
				(justify mirror)
			)
		)
		(duplicate_pad_numbers_are_jumpers no)
		(fp_rect
			(start 0.9398 0.9652)
			(end -0.9398 -0.9652)
			(stroke
				(width 0)
				(type default)
			)
			(fill no)
			(layer "B.CrtYd")
		)
		(fp_rect
			(start 0.9398 0.9652)
			(end -0.9398 -0.9652)
			(stroke
				(width 0)
				(type default)
			)
			(fill no)
			(layer "B.Fab")
		)
		(pad "1" smd custom
			(at 0 -0.5334 180)
			(size 0.17145 0.17145)
			(layers "B.Cu" "B.Mask" "B.Paste")
			(net "AGND_P5V_A")
			(options
				(clearance outline)
				(anchor circle)
			)
			(primitives
				(gr_poly
					(pts
						(xy -0.127 -0.3429) (xy -0.127 -0.1651) (xy -0.635 0.3429) (xy 0.635 0.3429) (xy 0.127 -0.1651)
						(xy 0.127 -0.3429)
					)
					(width 0)
					(fill yes)
				)
			)
		)
		(pad "2" smd custom
			(at 0 0.5334 180)
			(size 0.17145 0.17145)
			(layers "B.Cu" "B.Mask" "B.Paste")
			(net "GND")
			(options
				(clearance outline)
				(anchor circle)
			)
			(primitives
				(gr_poly
					(pts
						(xy -0.635 -0.3429) (xy -0.127 0.1651) (xy -0.127 0.3429) (xy 0.127 0.3429) (xy 0.127 0.1651)
						(xy 0.635 -0.3429)
					)
					(width 0)
					(fill yes)
				)
			)
		)
	)
)
